(kicad_pcb
	(version 20260206)
	(generator "pcbnew")
	(generator_version "10.0")
	(general
		(thickness 1.6)
		(legacy_teardrops no)
	)
	(paper "A4")
	(title_block
		(title "netronome-mezz — pcbd0082-001_rev01_jul9_a.brd")
		(comment 1 "Open CloudServer (Microsoft) / footprints 333-336 of 714")
	)
	(layers
		(0 "F.Cu" signal "TOP")
		(4 "In1.Cu" signal "02_GND")
		(6 "In2.Cu" signal "03_SIG")
		(8 "In3.Cu" signal "04_SIG")
		(10 "In4.Cu" signal "05_GND")
		(12 "In5.Cu" signal "06_PWR1")
		(14 "In6.Cu" signal "07_SIG")
		(16 "In7.Cu" signal "08_SIG")
		(18 "In8.Cu" signal "09_GND")
		(2 "B.Cu" signal "BOTTOM")
		(9 "F.Adhes" user "F.Adhesive")
		(11 "B.Adhes" user "B.Adhesive")
		(13 "F.Paste" user "Package Geometry/Pastemask Top")
		(15 "B.Paste" user "Package Geometry/Pastemask Bottom")
		(5 "F.SilkS" user "Ref Des/Silkscreen Top")
		(7 "B.SilkS" user "Ref Des/Silkscreen Bottom")
		(1 "F.Mask" user "Board Geometry/Soldermask Top")
		(3 "B.Mask" user "Board Geometry/Soldermask Bottom")
		(17 "Dwgs.User" user "User.Drawings")
		(19 "Cmts.User" user "User.Comments")
		(21 "Eco1.User" user "User.Eco1")
		(23 "Eco2.User" user "User.Eco2")
		(25 "Edge.Cuts" user "Board Geometry/Outline")
		(27 "Margin" user)
		(31 "F.CrtYd" user "Package Geometry/Place Bound Top")
		(29 "B.CrtYd" user "Package Geometry/Place Bound Bottom")
		(35 "F.Fab" user "Ref Des/Assembly Top")
		(33 "B.Fab" user "Ref Des/Assembly Bottom")
		(45 "User.4" user "COMPVAL_TYPE_BOTTOM")
	)
	(footprint ""
		(layer "B.Cu")
		(at 66.675 35.6362 180)
		(property "Reference" "C202"
			(at 0 0 0)
			(layer "B.SilkS")
			(hide yes)
			(effects
				(font
					(size 1.27 1.27)
				)
				(justify mirror)
			)
		)
		(property "Value" "1UF"
			(at 0.091846 0.2921 90)
			(unlocked yes)
			(layer "B.Fab")
			(hide yes)
			(effects
				(font
					(size 0.7874 0.5842)
					(thickness 0.2032)
				)
				(justify left mirror)
			)
		)
		(property "Device Type" "CAPC0028"
			(at 0.091846 0.2921 90)
			(unlocked yes)
			(layer "B.Fab")
			(hide yes)
			(effects
				(font
					(size 0.7874 0.5842)
					(thickness 0.2032)
				)
				(justify left mirror)
			)
		)
		(duplicate_pad_numbers_are_jumpers no)
		(fp_poly
			(pts
				(xy -0.635 1.0668) (xy -0.635 -1.0668) (xy 0.635 -1.0668) (xy 0.635 1.0668)
			)
			(stroke
				(width 0)
				(type default)
			)
			(fill no)
			(layer "B.CrtYd")
		)
		(fp_line
			(start 0.254 0.508)
			(end 0.254 -0.508)
			(stroke
				(width 0.0254)
				(type default)
			)
			(layer "B.Fab")
		)
		(fp_line
			(start 0.254 -0.508)
			(end -0.254 -0.508)
			(stroke
				(width 0.0254)
				(type default)
			)
			(layer "B.Fab")
		)
		(fp_line
			(start -0.254 0.508)
			(end 0.254 0.508)
			(stroke
				(width 0.0254)
				(type default)
			)
			(layer "B.Fab")
		)
		(fp_line
			(start -0.254 -0.508)
			(end -0.254 0.508)
			(stroke
				(width 0.0254)
				(type default)
			)
			(layer "B.Fab")
		)
		(pad "1" smd rect
			(at 0 -0.4191)
			(size 0.508 0.5334)
			(layers "B.Cu" "B.Mask" "B.Paste")
			(net "VDD_5.0V")
		)
		(pad "2" smd rect
			(at 0 0.4191)
			(size 0.508 0.5334)
			(layers "B.Cu" "B.Mask" "B.Paste")
			(net "GND")
		)
		(zone
			(layer "B.Cu")
			(hatch none 0.5)
			(connect_pads
				(clearance 0)
			)
			(min_thickness 0.25)
			(keepout
				(tracks not_allowed)
				(vias allowed)
				(pads allowed)
				(copperpour not_allowed)
				(footprints allowed)
			)
			(placement
				(enabled no)
				(sheetname "")
			)
			(fill
				(thermal_gap 0.5)
				(thermal_bridge_width 0.5)
				(island_removal_mode 0)
			)
			(polygon
				(pts
					(xy 66.7004 35.6616) (xy 66.7004 35.6108) (xy 66.6496 35.6108) (xy 66.6496 35.6616)
				)
			)
		)
	)
	(footprint ""
		(layer "B.Cu")
		(at 34.544 32.639)
		(property "Reference" "R173"
			(at 0 0 0)
			(layer "B.SilkS")
			(hide yes)
			(effects
				(font
					(size 1.27 1.27)
				)
				(justify mirror)
			)
		)
		(property "Value" "0"
			(at 0.148158 1.3462 270)
			(unlocked yes)
			(layer "B.Fab")
			(hide yes)
			(effects
				(font
					(size 1.27 0.9652)
					(thickness 0.000001)
				)
				(justify left mirror)
			)
		)
		(property "Device Type" "REST1111"
			(at 0.148158 1.3462 270)
			(unlocked yes)
			(layer "B.Fab")
			(hide yes)
			(effects
				(font
					(size 1.27 0.9652)
					(thickness 0.000001)
				)
				(justify left mirror)
			)
		)
		(duplicate_pad_numbers_are_jumpers no)
		(fp_poly
			(pts
				(xy -0.635 1.0668) (xy -0.635 -1.0668) (xy 0.635 -1.0668) (xy 0.635 1.0668)
			)
			(stroke
				(width 0)
				(type default)
			)
			(fill no)
			(layer "B.CrtYd")
		)
		(fp_line
			(start -0.254 -0.508)
			(end -0.254 0.508)
			(stroke
				(width 0.0254)
				(type default)
			)
			(layer "B.Fab")
		)
		(fp_line
			(start -0.254 0.508)
			(end 0.254 0.508)
			(stroke
				(width 0.0254)
				(type default)
			)
			(layer "B.Fab")
		)
		(fp_line
			(start 0.254 -0.508)
			(end -0.254 -0.508)
			(stroke
				(width 0.0254)
				(type default)
			)
			(layer "B.Fab")
		)
		(fp_line
			(start 0.254 0.508)
			(end 0.254 -0.508)
			(stroke
				(width 0.0254)
				(type default)
			)
			(layer "B.Fab")
		)
		(pad "1" smd rect
			(at 0 -0.4191 180)
			(size 0.508 0.5334)
			(layers "B.Cu" "B.Mask" "B.Paste")
			(net "NFP_CORE_VID6")
		)
		(pad "2" smd rect
			(at 0 0.4191 180)
			(size 0.508 0.5334)
			(layers "B.Cu" "B.Mask" "B.Paste")
			(net "_NFP_CORE_VID6")
		)
		(zone
			(layer "B.Cu")
			(hatch none 0.5)
			(connect_pads
				(clearance 0)
			)
			(min_thickness 0.25)
			(keepout
				(tracks not_allowed)
				(vias allowed)
				(pads allowed)
				(copperpour not_allowed)
				(footprints allowed)
			)
			(placement
				(enabled no)
				(sheetname "")
			)
			(fill
				(thermal_gap 0.5)
				(thermal_bridge_width 0.5)
				(island_removal_mode 0)
			)
			(polygon
				(pts
					(xy 34.5186 32.6136) (xy 34.5186 32.6644) (xy 34.5694 32.6644) (xy 34.5694 32.6136)
				)
			)
		)
	)
	(footprint ""
		(layer "B.Cu")
		(at 59.373008 0.762 180)
		(property "Reference" "C157"
			(at 0.145212 0.8763 270)
			(unlocked yes)
			(layer "B.SilkS")
			(effects
				(font
					(size 0.7874 0.5842)
					(thickness 0.127)
				)
				(justify left mirror)
			)
		)
		(property "Value" "0.22UF"
			(at 0.091846 0.2921 90)
			(unlocked yes)
			(layer "B.Fab")
			(hide yes)
			(effects
				(font
					(size 0.7874 0.5842)
					(thickness 0.2032)
				)
				(justify left mirror)
			)
		)
		(property "Device Type" "CAPC0062"
			(at 0.091846 0.2921 90)
			(unlocked yes)
			(layer "B.Fab")
			(hide yes)
			(effects
				(font
					(size 0.7874 0.5842)
					(thickness 0.2032)
				)
				(justify left mirror)
			)
		)
		(duplicate_pad_numbers_are_jumpers no)
		(fp_poly
			(pts
				(xy -0.635 1.0668) (xy -0.635 -1.0668) (xy 0.635 -1.0668) (xy 0.635 1.0668)
			)
			(stroke
				(width 0)
				(type default)
			)
			(fill no)
			(layer "B.CrtYd")
		)
		(fp_line
			(start 0.254 0.508)
			(end 0.254 -0.508)
			(stroke
				(width 0.0254)
				(type default)
			)
			(layer "B.Fab")
		)
		(fp_line
			(start 0.254 -0.508)
			(end -0.254 -0.508)
			(stroke
				(width 0.0254)
				(type default)
			)
			(layer "B.Fab")
		)
		(fp_line
			(start -0.254 0.508)
			(end 0.254 0.508)
			(stroke
				(width 0.0254)
				(type default)
			)
			(layer "B.Fab")
		)
		(fp_line
			(start -0.254 -0.508)
			(end -0.254 0.508)
			(stroke
				(width 0.0254)
				(type default)
			)
			(layer "B.Fab")
		)
		(pad "1" smd rect
			(at 0 -0.4191)
			(size 0.508 0.5334)
			(layers "B.Cu" "B.Mask" "B.Paste")
			(net "_NFP_PCIE0_PER2_P")
		)
		(pad "2" smd rect
			(at 0 0.4191)
			(size 0.508 0.5334)
			(layers "B.Cu" "B.Mask" "B.Paste")
			(net "NFP_PCIE0_PER2_P")
		)
		(zone
			(layer "B.Cu")
			(hatch none 0.5)
			(connect_pads
				(clearance 0)
			)
			(min_thickness 0.25)
			(keepout
				(tracks not_allowed)
				(vias allowed)
				(pads allowed)
				(copperpour not_allowed)
				(footprints allowed)
			)
			(placement
				(enabled no)
				(sheetname "")
			)
			(fill
				(thermal_gap 0.5)
				(thermal_bridge_width 0.5)
				(island_removal_mode 0)
			)
			(polygon
				(pts
					(xy 59.398408 0.7874) (xy 59.398408 0.7366) (xy 59.347608 0.7366) (xy 59.347608 0.7874)
				)
			)
		)
	)
	(footprint ""
		(layer "B.Cu")
		(at 83.450989 2.699004)
		(property "Reference" "V1_A-A09"
			(at 0 0 0)
			(layer "B.SilkS")
			(hide yes)
			(effects
				(font
					(size 1.27 1.27)
				)
				(justify mirror)
			)
		)
		(property "Value" ""
			(at 0 0 0)
			(layer "B.Fab")
			(effects
				(font
					(size 1.27 1.27)
				)
				(justify mirror)
			)
		)
		(duplicate_pad_numbers_are_jumpers no)
		(pad "1" thru_hole circle
			(at 0 0 180)
			(size 0.4572 0.4572)
			(drill 0.20574)
			(layers "*.Cu" "*.Mask")
			(remove_unused_layers no)
			(net "DDR0_32A_A9")
			(clearance 0.1143)
			(thermal_gap 0.1143)
		)
	)
)
